(kicad_pcb
	(version 20260206)
	(generator "pcbnew")
	(generator_version "10.0")
	(general
		(thickness 1.6)
		(legacy_teardrops no)
	)
	(paper "A4")
	(title_block
		(title "panther-plus-userver — 13130-1b_20150205.brd")
		(comment 1 "Honey Badger (Wiwynn) / footprint 624 of 1509 (DIMM4), pads 72-78 of 210")
	)
	(layers
		(0 "F.Cu" signal "TOP")
		(4 "In1.Cu" signal "L2")
		(6 "In2.Cu" signal "L3")
		(8 "In3.Cu" signal "L4")
		(10 "In4.Cu" signal "L5")
		(12 "In5.Cu" signal "L6")
		(14 "In6.Cu" signal "L7")
		(16 "In7.Cu" signal "L8")
		(18 "In8.Cu" signal "L9")
		(20 "In9.Cu" signal "L10")
		(22 "In10.Cu" signal "L11")
		(2 "B.Cu" signal "BOTTOM")
		(9 "F.Adhes" user "F.Adhesive")
		(11 "B.Adhes" user "B.Adhesive")
		(13 "F.Paste" user "Package Geometry/Pastemask Top")
		(15 "B.Paste" user "Package Geometry/Pastemask Bottom")
		(5 "F.SilkS" user "Ref Des/Silkscreen Top")
		(7 "B.SilkS" user "Ref Des/Silkscreen Bottom")
		(1 "F.Mask" user "Board Geometry/Soldermask Top")
		(3 "B.Mask" user "Board Geometry/Soldermask Bottom")
		(17 "Dwgs.User" user "User.Drawings")
		(19 "Cmts.User" user "User.Comments")
		(21 "Eco1.User" user "User.Eco1")
		(23 "Eco2.User" user "User.Eco2")
		(25 "Edge.Cuts" user "Board Geometry/Outline")
		(27 "Margin" user)
		(31 "F.CrtYd" user "Package Geometry/Place Bound Top")
		(29 "B.CrtYd" user "Package Geometry/Place Bound Bottom")
		(35 "F.Fab" user "Ref Des/Assembly Top")
		(33 "B.Fab" user "Ref Des/Assembly Bottom")
	)
	(footprint ""
		(layer "F.Cu")
		(at 159.999934 -5.790692)
		(property "Reference" "DIMM4"
			(at 0 0 0)
			(layer "F.SilkS")
			(hide yes)
			(effects
				(font
					(size 1.27 1.27)
				)
			)
		)
		(property "Value" "DDR3-204P-174-COLAY-1-GP"
			(at -40.682164 -17.468088 0)
			(unlocked yes)
			(layer "F.Fab")
			(hide yes)
			(effects
				(font
					(size 1.016 1.016)
					(thickness 0.1524)
				)
			)
		)
		(property "Device Type" "AS0A626-H8SN-7H-COLAY-1"
			(at -40.682164 -18.992088 0)
			(unlocked yes)
			(layer "F.Fab")
			(hide yes)
			(effects
				(font
					(size 1.016 1.016)
					(thickness 0.1524)
				)
			)
		)
		(duplicate_pad_numbers_are_jumpers no)
		(pad "70" smd custom
			(at -10.94994 -4.106672)
			(size 0.1143 0.1143)
			(layers "F.Cu" "F.Mask" "F.Paste")
			(net "GND")
			(options
				(clearance outline)
				(anchor circle)
			)
			(primitives
				(gr_poly
					(pts
						(xy 0 0.9017) (xy -0.03175 0.89916) (xy -0.0635 0.889) (xy -0.09144 0.87376) (xy -0.11684 0.85344)
						(xy -0.13716 0.82804) (xy -0.1524 0.8001) (xy -0.16256 0.76835) (xy -0.1651 0.7366) (xy -0.1651 0.44958)
						(xy -0.17272 0.44196) (xy -0.19812 0.4064) (xy -0.2032 0.39624) (xy -0.20701 0.38735) (xy -0.21209 0.37719)
						(xy -0.2159 0.36703) (xy -0.21844 0.35687) (xy -0.22225 0.34544) (xy -0.22352 0.33528) (xy -0.22606 0.32512)
						(xy -0.22733 0.31369) (xy -0.22733 0.30353) (xy -0.2286 0.2921) (xy -0.22733 0.28067) (xy -0.22733 0.27051)
						(xy -0.22606 0.25908) (xy -0.22352 0.24892) (xy -0.22225 0.23876) (xy -0.21844 0.22733) (xy -0.2159 0.21717)
						(xy -0.21209 0.20701) (xy -0.20701 0.19685) (xy -0.2032 0.18796) (xy -0.19812 0.1778) (xy -0.17272 0.14224)
						(xy -0.1651 0.13462) (xy -0.1651 -0.7366) (xy -0.16256 -0.76835) (xy -0.1524 -0.8001) (xy -0.13716 -0.82804)
						(xy -0.11684 -0.85344) (xy -0.09144 -0.87376) (xy -0.0635 -0.889) (xy -0.03175 -0.89916) (xy 0 -0.9017)
						(xy 0.03175 -0.89916) (xy 0.0635 -0.889) (xy 0.09144 -0.87376) (xy 0.11684 -0.85344) (xy 0.13716 -0.82804)
						(xy 0.1524 -0.8001) (xy 0.16256 -0.76835) (xy 0.1651 -0.7366) (xy 0.1651 0.13462) (xy 0.17272 0.14224)
						(xy 0.19812 0.1778) (xy 0.2032 0.18796) (xy 0.20701 0.19685) (xy 0.21209 0.20701) (xy 0.2159 0.21717)
						(xy 0.21844 0.22733) (xy 0.22225 0.23876) (xy 0.22352 0.24892) (xy 0.22606 0.25908) (xy 0.22733 0.27051)
						(xy 0.22733 0.28067) (xy 0.2286 0.2921) (xy 0.22733 0.30353) (xy 0.22733 0.31369) (xy 0.22606 0.32512)
						(xy 0.22352 0.33528) (xy 0.22225 0.34544) (xy 0.21844 0.35687) (xy 0.2159 0.36703) (xy 0.21209 0.37719)
						(xy 0.20701 0.38735) (xy 0.2032 0.39624) (xy 0.19812 0.4064) (xy 0.17272 0.44196) (xy 0.1651 0.44958)
						(xy 0.1651 0.7366) (xy 0.16256 0.76835) (xy 0.1524 0.8001) (xy 0.13716 0.82804) (xy 0.11684 0.85344)
						(xy 0.09144 0.87376) (xy 0.0635 0.889) (xy 0.03175 0.89916)
					)
					(width 0)
					(fill yes)
				)
			)
		)
		(pad "71" smd custom
			(at -10.649966 4.106672)
			(size 0.1143 0.1143)
			(layers "F.Cu" "F.Mask" "F.Paste")
			(net "M_B_ECC5")
			(options
				(clearance outline)
				(anchor circle)
			)
			(primitives
				(gr_poly
					(pts
						(xy 0 0.9017) (xy -0.03175 0.89916) (xy -0.0635 0.889) (xy -0.09144 0.87376) (xy -0.11684 0.85344)
						(xy -0.13716 0.82804) (xy -0.1524 0.8001) (xy -0.16256 0.76835) (xy -0.1651 0.7366) (xy -0.1651 0.11938)
						(xy -0.17272 0.11176) (xy -0.19812 0.0762) (xy -0.2032 0.06604) (xy -0.20701 0.05715) (xy -0.21209 0.04699)
						(xy -0.2159 0.03683) (xy -0.21844 0.02667) (xy -0.22225 0.01524) (xy -0.22352 0.00508) (xy -0.22606 -0.00508)
						(xy -0.22733 -0.01651) (xy -0.22733 -0.02667) (xy -0.2286 -0.0381) (xy -0.22733 -0.04953) (xy -0.22733 -0.05969)
						(xy -0.22606 -0.07112) (xy -0.22352 -0.08128) (xy -0.22225 -0.09144) (xy -0.21844 -0.10287) (xy -0.2159 -0.11303)
						(xy -0.21209 -0.12319) (xy -0.20701 -0.13335) (xy -0.2032 -0.14224) (xy -0.19812 -0.1524) (xy -0.17272 -0.18796)
						(xy -0.1651 -0.19558) (xy -0.1651 -0.7366) (xy -0.16256 -0.76835) (xy -0.1524 -0.8001) (xy -0.13716 -0.82804)
						(xy -0.11684 -0.85344) (xy -0.09144 -0.87376) (xy -0.0635 -0.889) (xy -0.03175 -0.89916) (xy 0 -0.9017)
						(xy 0.03175 -0.89916) (xy 0.0635 -0.889) (xy 0.09144 -0.87376) (xy 0.11684 -0.85344) (xy 0.13716 -0.82804)
						(xy 0.1524 -0.8001) (xy 0.16256 -0.76835) (xy 0.1651 -0.7366) (xy 0.1651 -0.19685) (xy 0.17272 -0.18923)
						(xy 0.17907 -0.18034) (xy 0.18669 -0.17145) (xy 0.19177 -0.16256) (xy 0.19812 -0.15367) (xy 0.20828 -0.13335)
						(xy 0.21971 -0.10287) (xy 0.22225 -0.09271) (xy 0.22479 -0.08128) (xy 0.22606 -0.07112) (xy 0.2286 -0.05969)
						(xy 0.2286 -0.01651) (xy 0.22606 -0.00508) (xy 0.22479 0.00508) (xy 0.22225 0.01651) (xy 0.21971 0.02667)
						(xy 0.20828 0.05715) (xy 0.19812 0.07747) (xy 0.19177 0.08636) (xy 0.18669 0.09525) (xy 0.17907 0.10414)
						(xy 0.17272 0.11303) (xy 0.1651 0.12065) (xy 0.1651 0.7366) (xy 0.16256 0.76835) (xy 0.1524 0.8001)
						(xy 0.13716 0.82804) (xy 0.11684 0.85344) (xy 0.09144 0.87376) (xy 0.0635 0.889) (xy 0.03175 0.89916)
					)
					(width 0)
					(fill yes)
				)
			)
		)
		(pad "72" smd custom
			(at -10.349992 -4.106672)
			(size 0.1143 0.1143)
			(layers "F.Cu" "F.Mask" "F.Paste")
			(net "M_B_ECC0")
			(options
				(clearance outline)
				(anchor circle)
			)
			(primitives
				(gr_poly
					(pts
						(xy 0 0.9017) (xy -0.03175 0.89916) (xy -0.0635 0.889) (xy -0.09144 0.87376) (xy -0.11684 0.85344)
						(xy -0.13716 0.82804) (xy -0.1524 0.8001) (xy -0.16256 0.76835) (xy -0.1651 0.7366) (xy -0.1651 0.19685)
						(xy -0.17272 0.18923) (xy -0.17907 0.18034) (xy -0.18669 0.17145) (xy -0.19177 0.16256) (xy -0.19812 0.15367)
						(xy -0.20828 0.13335) (xy -0.21971 0.10287) (xy -0.22225 0.09271) (xy -0.22479 0.08128) (xy -0.22606 0.07112)
						(xy -0.2286 0.05969) (xy -0.2286 0.01651) (xy -0.22606 0.00508) (xy -0.22479 -0.00508) (xy -0.22225 -0.01651)
						(xy -0.21971 -0.02667) (xy -0.20828 -0.05715) (xy -0.19812 -0.07747) (xy -0.19177 -0.08636) (xy -0.18669 -0.09525)
						(xy -0.17907 -0.10414) (xy -0.17272 -0.11303) (xy -0.1651 -0.12065) (xy -0.1651 -0.7366) (xy -0.16256 -0.76835)
						(xy -0.1524 -0.8001) (xy -0.13716 -0.82804) (xy -0.11684 -0.85344) (xy -0.09144 -0.87376) (xy -0.0635 -0.889)
						(xy -0.03175 -0.89916) (xy 0 -0.9017) (xy 0.03175 -0.89916) (xy 0.0635 -0.889) (xy 0.09144 -0.87376)
						(xy 0.11684 -0.85344) (xy 0.13716 -0.82804) (xy 0.1524 -0.8001) (xy 0.16256 -0.76835) (xy 0.1651 -0.7366)
						(xy 0.1651 -0.11938) (xy 0.17272 -0.11176) (xy 0.19812 -0.0762) (xy 0.2032 -0.06604) (xy 0.20701 -0.05715)
						(xy 0.21209 -0.04699) (xy 0.2159 -0.03683) (xy 0.21844 -0.02667) (xy 0.22225 -0.01524) (xy 0.22352 -0.00508)
						(xy 0.22606 0.00508) (xy 0.22733 0.01651) (xy 0.22733 0.02667) (xy 0.2286 0.0381) (xy 0.22733 0.04953)
						(xy 0.22733 0.05969) (xy 0.22606 0.07112) (xy 0.22352 0.08128) (xy 0.22225 0.09144) (xy 0.21844 0.10287)
						(xy 0.2159 0.11303) (xy 0.21209 0.12319) (xy 0.20701 0.13335) (xy 0.2032 0.14224) (xy 0.19812 0.1524)
						(xy 0.17272 0.18796) (xy 0.1651 0.19558) (xy 0.1651 0.7366) (xy 0.16256 0.76835) (xy 0.1524 0.8001)
						(xy 0.13716 0.82804) (xy 0.11684 0.85344) (xy 0.09144 0.87376) (xy 0.0635 0.889) (xy 0.03175 0.89916)
					)
					(width 0)
					(fill yes)
				)
			)
		)
		(pad "73" smd custom
			(at -7.649972 4.106672)
			(size 0.1143 0.1143)
			(layers "F.Cu" "F.Mask" "F.Paste")
			(net "GND")
			(options
				(clearance outline)
				(anchor circle)
			)
			(primitives
				(gr_poly
					(pts
						(xy 0 0.9017) (xy -0.03175 0.89916) (xy -0.0635 0.889) (xy -0.09144 0.87376) (xy -0.11684 0.85344)
						(xy -0.13716 0.82804) (xy -0.1524 0.8001) (xy -0.16256 0.76835) (xy -0.1651 0.7366) (xy -0.1651 -0.13462)
						(xy -0.17272 -0.14224) (xy -0.19812 -0.1778) (xy -0.2032 -0.18796) (xy -0.20701 -0.19685) (xy -0.21209 -0.20701)
						(xy -0.2159 -0.21717) (xy -0.21844 -0.22733) (xy -0.22225 -0.23876) (xy -0.22352 -0.24892) (xy -0.22606 -0.25908)
						(xy -0.22733 -0.27051) (xy -0.22733 -0.28067) (xy -0.2286 -0.2921) (xy -0.22733 -0.30353) (xy -0.22733 -0.31369)
						(xy -0.22606 -0.32512) (xy -0.22352 -0.33528) (xy -0.22225 -0.34544) (xy -0.21844 -0.35687) (xy -0.2159 -0.36703)
						(xy -0.21209 -0.37719) (xy -0.20701 -0.38735) (xy -0.2032 -0.39624) (xy -0.19812 -0.4064) (xy -0.17272 -0.44196)
						(xy -0.1651 -0.44958) (xy -0.1651 -0.7366) (xy -0.16256 -0.76835) (xy -0.1524 -0.8001) (xy -0.13716 -0.82804)
						(xy -0.11684 -0.85344) (xy -0.09144 -0.87376) (xy -0.0635 -0.889) (xy -0.03175 -0.89916) (xy 0 -0.9017)
						(xy 0.03175 -0.89916) (xy 0.0635 -0.889) (xy 0.09144 -0.87376) (xy 0.11684 -0.85344) (xy 0.13716 -0.82804)
						(xy 0.1524 -0.8001) (xy 0.16256 -0.76835) (xy 0.1651 -0.7366) (xy 0.1651 -0.44958) (xy 0.17272 -0.44196)
						(xy 0.19812 -0.4064) (xy 0.2032 -0.39624) (xy 0.20701 -0.38735) (xy 0.21209 -0.37719) (xy 0.2159 -0.36703)
						(xy 0.21844 -0.35687) (xy 0.22225 -0.34544) (xy 0.22352 -0.33528) (xy 0.22606 -0.32512) (xy 0.22733 -0.31369)
						(xy 0.22733 -0.30353) (xy 0.2286 -0.2921) (xy 0.22733 -0.28067) (xy 0.22733 -0.27051) (xy 0.22606 -0.25908)
						(xy 0.22352 -0.24892) (xy 0.22225 -0.23876) (xy 0.21844 -0.22733) (xy 0.2159 -0.21717) (xy 0.21209 -0.20701)
						(xy 0.20701 -0.19685) (xy 0.2032 -0.18796) (xy 0.19812 -0.1778) (xy 0.17272 -0.14224) (xy 0.1651 -0.13462)
						(xy 0.1651 0.7366) (xy 0.16256 0.76835) (xy 0.1524 0.8001) (xy 0.13716 0.82804) (xy 0.11684 0.85344)
						(xy 0.09144 0.87376) (xy 0.0635 0.889) (xy 0.03175 0.89916)
					)
					(width 0)
					(fill yes)
				)
			)
		)
		(pad "74" smd custom
			(at -7.349998 -4.106672)
			(size 0.1143 0.1143)
			(layers "F.Cu" "F.Mask" "F.Paste")
			(net "M_B_ECC1")
			(options
				(clearance outline)
				(anchor circle)
			)
			(primitives
				(gr_poly
					(pts
						(xy 0 0.9017) (xy -0.03175 0.89916) (xy -0.0635 0.889) (xy -0.09144 0.87376) (xy -0.11684 0.85344)
						(xy -0.13716 0.82804) (xy -0.1524 0.8001) (xy -0.16256 0.76835) (xy -0.1651 0.7366) (xy -0.1651 0.44958)
						(xy -0.17272 0.44196) (xy -0.19812 0.4064) (xy -0.2032 0.39624) (xy -0.20701 0.38735) (xy -0.21209 0.37719)
						(xy -0.2159 0.36703) (xy -0.21844 0.35687) (xy -0.22225 0.34544) (xy -0.22352 0.33528) (xy -0.22606 0.32512)
						(xy -0.22733 0.31369) (xy -0.22733 0.30353) (xy -0.2286 0.2921) (xy -0.22733 0.28067) (xy -0.22733 0.27051)
						(xy -0.22606 0.25908) (xy -0.22352 0.24892) (xy -0.22225 0.23876) (xy -0.21844 0.22733) (xy -0.2159 0.21717)
						(xy -0.21209 0.20701) (xy -0.20701 0.19685) (xy -0.2032 0.18796) (xy -0.19812 0.1778) (xy -0.17272 0.14224)
						(xy -0.1651 0.13462) (xy -0.1651 -0.7366) (xy -0.16256 -0.76835) (xy -0.1524 -0.8001) (xy -0.13716 -0.82804)
						(xy -0.11684 -0.85344) (xy -0.09144 -0.87376) (xy -0.0635 -0.889) (xy -0.03175 -0.89916) (xy 0 -0.9017)
						(xy 0.03175 -0.89916) (xy 0.0635 -0.889) (xy 0.09144 -0.87376) (xy 0.11684 -0.85344) (xy 0.13716 -0.82804)
						(xy 0.1524 -0.8001) (xy 0.16256 -0.76835) (xy 0.1651 -0.7366) (xy 0.1651 0.13462) (xy 0.17272 0.14224)
						(xy 0.19812 0.1778) (xy 0.2032 0.18796) (xy 0.20701 0.19685) (xy 0.21209 0.20701) (xy 0.2159 0.21717)
						(xy 0.21844 0.22733) (xy 0.22225 0.23876) (xy 0.22352 0.24892) (xy 0.22606 0.25908) (xy 0.22733 0.27051)
						(xy 0.22733 0.28067) (xy 0.2286 0.2921) (xy 0.22733 0.30353) (xy 0.22733 0.31369) (xy 0.22606 0.32512)
						(xy 0.22352 0.33528) (xy 0.22225 0.34544) (xy 0.21844 0.35687) (xy 0.2159 0.36703) (xy 0.21209 0.37719)
						(xy 0.20701 0.38735) (xy 0.2032 0.39624) (xy 0.19812 0.4064) (xy 0.17272 0.44196) (xy 0.1651 0.44958)
						(xy 0.1651 0.7366) (xy 0.16256 0.76835) (xy 0.1524 0.8001) (xy 0.13716 0.82804) (xy 0.11684 0.85344)
						(xy 0.09144 0.87376) (xy 0.0635 0.889) (xy 0.03175 0.89916)
					)
					(width 0)
					(fill yes)
				)
			)
		)
		(pad "75" smd custom
			(at -7.050024 4.106672)
			(size 0.1143 0.1143)
			(layers "F.Cu" "F.Mask" "F.Paste")
			(net "M_B_DQS_DN8")
			(options
				(clearance outline)
				(anchor circle)
			)
			(primitives
				(gr_poly
					(pts
						(xy 0 0.9017) (xy -0.03175 0.89916) (xy -0.0635 0.889) (xy -0.09144 0.87376) (xy -0.11684 0.85344)
						(xy -0.13716 0.82804) (xy -0.1524 0.8001) (xy -0.16256 0.76835) (xy -0.1651 0.7366) (xy -0.1651 0.11938)
						(xy -0.17272 0.11176) (xy -0.19812 0.0762) (xy -0.2032 0.06604) (xy -0.20701 0.05715) (xy -0.21209 0.04699)
						(xy -0.2159 0.03683) (xy -0.21844 0.02667) (xy -0.22225 0.01524) (xy -0.22352 0.00508) (xy -0.22606 -0.00508)
						(xy -0.22733 -0.01651) (xy -0.22733 -0.02667) (xy -0.2286 -0.0381) (xy -0.22733 -0.04953) (xy -0.22733 -0.05969)
						(xy -0.22606 -0.07112) (xy -0.22352 -0.08128) (xy -0.22225 -0.09144) (xy -0.21844 -0.10287) (xy -0.2159 -0.11303)
						(xy -0.21209 -0.12319) (xy -0.20701 -0.13335) (xy -0.2032 -0.14224) (xy -0.19812 -0.1524) (xy -0.17272 -0.18796)
						(xy -0.1651 -0.19558) (xy -0.1651 -0.7366) (xy -0.16256 -0.76835) (xy -0.1524 -0.8001) (xy -0.13716 -0.82804)
						(xy -0.11684 -0.85344) (xy -0.09144 -0.87376) (xy -0.0635 -0.889) (xy -0.03175 -0.89916) (xy 0 -0.9017)
						(xy 0.03175 -0.89916) (xy 0.0635 -0.889) (xy 0.09144 -0.87376) (xy 0.11684 -0.85344) (xy 0.13716 -0.82804)
						(xy 0.1524 -0.8001) (xy 0.16256 -0.76835) (xy 0.1651 -0.7366) (xy 0.1651 -0.19685) (xy 0.17272 -0.18923)
						(xy 0.17907 -0.18034) (xy 0.18669 -0.17145) (xy 0.19177 -0.16256) (xy 0.19812 -0.15367) (xy 0.20828 -0.13335)
						(xy 0.21971 -0.10287) (xy 0.22225 -0.09271) (xy 0.22479 -0.08128) (xy 0.22606 -0.07112) (xy 0.2286 -0.05969)
						(xy 0.2286 -0.01651) (xy 0.22606 -0.00508) (xy 0.22479 0.00508) (xy 0.22225 0.01651) (xy 0.21971 0.02667)
						(xy 0.20828 0.05715) (xy 0.19812 0.07747) (xy 0.19177 0.08636) (xy 0.18669 0.09525) (xy 0.17907 0.10414)
						(xy 0.17272 0.11303) (xy 0.1651 0.12065) (xy 0.1651 0.7366) (xy 0.16256 0.76835) (xy 0.1524 0.8001)
						(xy 0.13716 0.82804) (xy 0.11684 0.85344) (xy 0.09144 0.87376) (xy 0.0635 0.889) (xy 0.03175 0.89916)
					)
					(width 0)
					(fill yes)
				)
			)
		)
		(pad "76" smd custom
			(at -6.75005 -4.106672)
			(size 0.1143 0.1143)
			(layers "F.Cu" "F.Mask" "F.Paste")
			(net "GND")
			(options
				(clearance outline)
				(anchor circle)
			)
			(primitives
				(gr_poly
					(pts
						(xy 0 0.9017) (xy -0.03175 0.89916) (xy -0.0635 0.889) (xy -0.09144 0.87376) (xy -0.11684 0.85344)
						(xy -0.13716 0.82804) (xy -0.1524 0.8001) (xy -0.16256 0.76835) (xy -0.1651 0.7366) (xy -0.1651 0.19685)
						(xy -0.17272 0.18923) (xy -0.17907 0.18034) (xy -0.18669 0.17145) (xy -0.19177 0.16256) (xy -0.19812 0.15367)
						(xy -0.20828 0.13335) (xy -0.21971 0.10287) (xy -0.22225 0.09271) (xy -0.22479 0.08128) (xy -0.22606 0.07112)
						(xy -0.2286 0.05969) (xy -0.2286 0.01651) (xy -0.22606 0.00508) (xy -0.22479 -0.00508) (xy -0.22225 -0.01651)
						(xy -0.21971 -0.02667) (xy -0.20828 -0.05715) (xy -0.19812 -0.07747) (xy -0.19177 -0.08636) (xy -0.18669 -0.09525)
						(xy -0.17907 -0.10414) (xy -0.17272 -0.11303) (xy -0.1651 -0.12065) (xy -0.1651 -0.7366) (xy -0.16256 -0.76835)
						(xy -0.1524 -0.8001) (xy -0.13716 -0.82804) (xy -0.11684 -0.85344) (xy -0.09144 -0.87376) (xy -0.0635 -0.889)
						(xy -0.03175 -0.89916) (xy 0 -0.9017) (xy 0.03175 -0.89916) (xy 0.0635 -0.889) (xy 0.09144 -0.87376)
						(xy 0.11684 -0.85344) (xy 0.13716 -0.82804) (xy 0.1524 -0.8001) (xy 0.16256 -0.76835) (xy 0.1651 -0.7366)
						(xy 0.1651 -0.11938) (xy 0.17272 -0.11176) (xy 0.19812 -0.0762) (xy 0.2032 -0.06604) (xy 0.20701 -0.05715)
						(xy 0.21209 -0.04699) (xy 0.2159 -0.03683) (xy 0.21844 -0.02667) (xy 0.22225 -0.01524) (xy 0.22352 -0.00508)
						(xy 0.22606 0.00508) (xy 0.22733 0.01651) (xy 0.22733 0.02667) (xy 0.2286 0.0381) (xy 0.22733 0.04953)
						(xy 0.22733 0.05969) (xy 0.22606 0.07112) (xy 0.22352 0.08128) (xy 0.22225 0.09144) (xy 0.21844 0.10287)
						(xy 0.2159 0.11303) (xy 0.21209 0.12319) (xy 0.20701 0.13335) (xy 0.2032 0.14224) (xy 0.19812 0.1524)
						(xy 0.17272 0.18796) (xy 0.1651 0.19558) (xy 0.1651 0.7366) (xy 0.16256 0.76835) (xy 0.1524 0.8001)
						(xy 0.13716 0.82804) (xy 0.11684 0.85344) (xy 0.09144 0.87376) (xy 0.0635 0.889) (xy 0.03175 0.89916)
					)
					(width 0)
					(fill yes)
				)
			)
		)
	)
)
